# T6G (Grand Teton) — schematic netlist excerpt (pin names and nets, part order shuffled) for the footprints in the layout excerpt that follows; sources: Cadence DE-HDL packaged netlist, KiCad conversion of 04192023_DAF0TMB3IC0_F0TG_MB_C_brd_V02_OCP.brd

C94  Q_CAP  4.7PF 50V 0.1P NPO  pkg C0402  page 233 : A = CLK_GEN2_XTAL_OUT ; B = GND

(kicad_pcb
	(version 20260206)
	(generator "pcbnew")
	(generator_version "10.0")
	(general
		(thickness 1.6)
		(legacy_teardrops no)
	)
	(paper "A4")
	(title_block
		(title "04192023_DAF0TMB3IC0_F0TG_MB_C_brd_V02_OCP.brd")
		(comment 1 "Grand Teton / footprints 1535-1535 of 8354")
	)
	(layers
		(0 "F.Cu" signal "TOP")
		(4 "In1.Cu" signal "GND")
		(6 "In2.Cu" signal "IN1")
		(8 "In3.Cu" signal "GND1")
		(10 "In4.Cu" signal "IN2")
		(12 "In5.Cu" signal "GND2")
		(14 "In6.Cu" signal "IN3")
		(16 "In7.Cu" signal "GND3")
		(18 "In8.Cu" signal "VCC")
		(20 "In9.Cu" signal "VCC1")
		(22 "In10.Cu" signal "GND4")
		(24 "In11.Cu" signal "IN4")
		(26 "In12.Cu" signal "GND5")
		(28 "In13.Cu" signal "IN5")
		(30 "In14.Cu" signal "GND6")
		(32 "In15.Cu" signal "IN6")
		(34 "In16.Cu" signal "GND7")
		(2 "B.Cu" signal "BOTTOM")
		(9 "F.Adhes" user "F.Adhesive")
		(11 "B.Adhes" user "B.Adhesive")
		(13 "F.Paste" user "Package Geometry/Pastemask Top")
		(15 "B.Paste" user "Package Geometry/Pastemask Bottom")
		(5 "F.SilkS" user "Ref Des/Silkscreen Top")
		(7 "B.SilkS" user "Ref Des/Silkscreen Bottom")
		(1 "F.Mask" user "Board Geometry/Soldermask Top")
		(3 "B.Mask" user "Board Geometry/Soldermask Bottom")
		(17 "Dwgs.User" user "User.Drawings")
		(19 "Cmts.User" user "User.Comments")
		(21 "Eco1.User" user "User.Eco1")
		(23 "Eco2.User" user "User.Eco2")
		(25 "Edge.Cuts" user "Board Geometry/Outline")
		(27 "Margin" user)
		(31 "F.CrtYd" user "Package Geometry/Place Bound Top")
		(29 "B.CrtYd" user "Package Geometry/Place Bound Bottom")
		(35 "F.Fab" user "Ref Des/Assembly Top")
		(33 "B.Fab" user "Ref Des/Assembly Bottom")
	)
	(footprint ""
		(layer "F.Cu")
		(at 8.324596 -133.95198 -90)
		(property "Reference" "C94"
			(at 0 0 270)
			(layer "F.SilkS")
			(hide yes)
			(effects
				(font
					(size 1.27 1.27)
				)
			)
		)
		(property "Value" ""
			(at 0 0 270)
			(layer "F.Fab")
			(effects
				(font
					(size 1.27 1.27)
				)
			)
		)
		(duplicate_pad_numbers_are_jumpers no)
		(fp_line
			(start -0.7874 0.4064)
			(end -0.7874 -0.4064)
			(stroke
				(width 0.1524)
				(type default)
			)
			(layer "F.SilkS")
		)
		(fp_line
			(start 0.7874 0.4064)
			(end -0.7874 0.4064)
			(stroke
				(width 0.1524)
				(type default)
			)
			(layer "F.SilkS")
		)
		(fp_line
			(start -0.7874 -0.4064)
			(end 0.7874 -0.4064)
			(stroke
				(width 0.1524)
				(type default)
			)
			(layer "F.SilkS")
		)
		(fp_line
			(start 0.7874 -0.4064)
			(end 0.7874 0.4064)
			(stroke
				(width 0.1524)
				(type default)
			)
			(layer "F.SilkS")
		)
		(fp_line
			(start -0.67945 0.3048)
			(end -0.67945 -0.305054)
			(stroke
				(width 0.1)
				(type default)
			)
			(layer "F.Fab")
		)
		(fp_line
			(start -0.12065 0.3048)
			(end -0.67945 0.3048)
			(stroke
				(width 0.1)
				(type default)
			)
			(layer "F.Fab")
		)
		(fp_line
			(start 0.120396 0.3048)
			(end 0.120396 0.2794)
			(stroke
				(width 0.1)
				(type default)
			)
			(layer "F.Fab")
		)
		(fp_line
			(start 0.67945 0.3048)
			(end 0.120396 0.3048)
			(stroke
				(width 0.1)
				(type default)
			)
			(layer "F.Fab")
		)
		(fp_line
			(start -0.12065 0.2794)
			(end -0.12065 0.3048)
			(stroke
				(width 0.1)
				(type default)
			)
			(layer "F.Fab")
		)
		(fp_line
			(start 0.120396 0.2794)
			(end -0.12065 0.2794)
			(stroke
				(width 0.1)
				(type default)
			)
			(layer "F.Fab")
		)
		(fp_line
			(start -0.12065 -0.2794)
			(end 0.12065 -0.2794)
			(stroke
				(width 0.1)
				(type default)
			)
			(layer "F.Fab")
		)
		(fp_line
			(start 0.12065 -0.2794)
			(end 0.12065 -0.3048)
			(stroke
				(width 0.1)
				(type default)
			)
			(layer "F.Fab")
		)
		(fp_line
			(start 0.12065 -0.3048)
			(end 0.67945 -0.3048)
			(stroke
				(width 0.1)
				(type default)
			)
			(layer "F.Fab")
		)
		(fp_line
			(start 0.67945 -0.3048)
			(end 0.67945 0.3048)
			(stroke
				(width 0.1)
				(type default)
			)
			(layer "F.Fab")
		)
		(fp_line
			(start -0.67945 -0.305054)
			(end -0.12065 -0.305054)
			(stroke
				(width 0.1)
				(type default)
			)
			(layer "F.Fab")
		)
		(fp_line
			(start -0.12065 -0.305054)
			(end -0.12065 -0.2794)
			(stroke
				(width 0.1)
				(type default)
			)
			(layer "F.Fab")
		)
		(pad "1" smd circle
			(at -0.40005 0 270)
			(size 0 0)
			(layers "F.Cu" "F.Mask" "F.Paste")
			(net "CLK_GEN2_XTAL_OUT")
		)
		(pad "2" smd circle
			(at 0.40005 0 270)
			(size 0 0)
			(layers "F.Cu" "F.Mask" "F.Paste")
			(net "GND")
		)
	)
)
